(kicad_pcb
	(version 20260206)
	(generator "pcbnew")
	(generator_version "10.0")
	(general
		(thickness 1.6)
		(legacy_teardrops no)
	)
	(paper "A4")
	(title_block
		(title "04192023_DAF0TMB3IC0_F0TG_MB_C_brd_V02_OCP.brd")
		(comment 1 "Grand Teton / footprints 1754-1759 of 8354")
	)
	(layers
		(0 "F.Cu" signal "TOP")
		(4 "In1.Cu" signal "GND")
		(6 "In2.Cu" signal "IN1")
		(8 "In3.Cu" signal "GND1")
		(10 "In4.Cu" signal "IN2")
		(12 "In5.Cu" signal "GND2")
		(14 "In6.Cu" signal "IN3")
		(16 "In7.Cu" signal "GND3")
		(18 "In8.Cu" signal "VCC")
		(20 "In9.Cu" signal "VCC1")
		(22 "In10.Cu" signal "GND4")
		(24 "In11.Cu" signal "IN4")
		(26 "In12.Cu" signal "GND5")
		(28 "In13.Cu" signal "IN5")
		(30 "In14.Cu" signal "GND6")
		(32 "In15.Cu" signal "IN6")
		(34 "In16.Cu" signal "GND7")
		(2 "B.Cu" signal "BOTTOM")
		(9 "F.Adhes" user "F.Adhesive")
		(11 "B.Adhes" user "B.Adhesive")
		(13 "F.Paste" user "Package Geometry/Pastemask Top")
		(15 "B.Paste" user "Package Geometry/Pastemask Bottom")
		(5 "F.SilkS" user "Ref Des/Silkscreen Top")
		(7 "B.SilkS" user "Ref Des/Silkscreen Bottom")
		(1 "F.Mask" user "Board Geometry/Soldermask Top")
		(3 "B.Mask" user "Board Geometry/Soldermask Bottom")
		(17 "Dwgs.User" user "User.Drawings")
		(19 "Cmts.User" user "User.Comments")
		(21 "Eco1.User" user "User.Eco1")
		(23 "Eco2.User" user "User.Eco2")
		(25 "Edge.Cuts" user "Board Geometry/Outline")
		(27 "Margin" user)
		(31 "F.CrtYd" user "Package Geometry/Place Bound Top")
		(29 "B.CrtYd" user "Package Geometry/Place Bound Bottom")
		(35 "F.Fab" user "Ref Des/Assembly Top")
		(33 "B.Fab" user "Ref Des/Assembly Bottom")
	)
	(footprint ""
		(layer "F.Cu")
		(at 288.26587 -96.655382)
		(property "Reference" "C1510"
			(at 0 0 0)
			(layer "F.SilkS")
			(hide yes)
			(effects
				(font
					(size 1.27 1.27)
				)
			)
		)
		(property "Value" ""
			(at 0 0 0)
			(layer "F.Fab")
			(effects
				(font
					(size 1.27 1.27)
				)
			)
		)
		(duplicate_pad_numbers_are_jumpers no)
		(fp_line
			(start -0.7874 -0.4064)
			(end 0.7874 -0.4064)
			(stroke
				(width 0.1524)
				(type default)
			)
			(layer "F.SilkS")
		)
		(fp_line
			(start -0.7874 0.4064)
			(end -0.7874 -0.4064)
			(stroke
				(width 0.1524)
				(type default)
			)
			(layer "F.SilkS")
		)
		(fp_line
			(start 0.7874 -0.4064)
			(end 0.7874 0.4064)
			(stroke
				(width 0.1524)
				(type default)
			)
			(layer "F.SilkS")
		)
		(fp_line
			(start 0.7874 0.4064)
			(end -0.7874 0.4064)
			(stroke
				(width 0.1524)
				(type default)
			)
			(layer "F.SilkS")
		)
		(fp_line
			(start -0.67945 -0.305054)
			(end -0.12065 -0.305054)
			(stroke
				(width 0.1)
				(type default)
			)
			(layer "F.Fab")
		)
		(fp_line
			(start -0.67945 0.3048)
			(end -0.67945 -0.305054)
			(stroke
				(width 0.1)
				(type default)
			)
			(layer "F.Fab")
		)
		(fp_line
			(start -0.12065 -0.305054)
			(end -0.12065 -0.2794)
			(stroke
				(width 0.1)
				(type default)
			)
			(layer "F.Fab")
		)
		(fp_line
			(start -0.12065 -0.2794)
			(end 0.12065 -0.2794)
			(stroke
				(width 0.1)
				(type default)
			)
			(layer "F.Fab")
		)
		(fp_line
			(start -0.12065 0.2794)
			(end -0.12065 0.3048)
			(stroke
				(width 0.1)
				(type default)
			)
			(layer "F.Fab")
		)
		(fp_line
			(start -0.12065 0.3048)
			(end -0.67945 0.3048)
			(stroke
				(width 0.1)
				(type default)
			)
			(layer "F.Fab")
		)
		(fp_line
			(start 0.120396 0.2794)
			(end -0.12065 0.2794)
			(stroke
				(width 0.1)
				(type default)
			)
			(layer "F.Fab")
		)
		(fp_line
			(start 0.120396 0.3048)
			(end 0.120396 0.2794)
			(stroke
				(width 0.1)
				(type default)
			)
			(layer "F.Fab")
		)
		(fp_line
			(start 0.12065 -0.3048)
			(end 0.67945 -0.3048)
			(stroke
				(width 0.1)
				(type default)
			)
			(layer "F.Fab")
		)
		(fp_line
			(start 0.12065 -0.2794)
			(end 0.12065 -0.3048)
			(stroke
				(width 0.1)
				(type default)
			)
			(layer "F.Fab")
		)
		(fp_line
			(start 0.67945 -0.3048)
			(end 0.67945 0.3048)
			(stroke
				(width 0.1)
				(type default)
			)
			(layer "F.Fab")
		)
		(fp_line
			(start 0.67945 0.3048)
			(end 0.120396 0.3048)
			(stroke
				(width 0.1)
				(type default)
			)
			(layer "F.Fab")
		)
		(pad "1" smd circle
			(at -0.40005 0)
			(size 0 0)
			(layers "F.Cu" "F.Mask" "F.Paste")
			(net "JTAG_TCK")
		)
		(pad "2" smd circle
			(at 0.40005 0)
			(size 0 0)
			(layers "F.Cu" "F.Mask" "F.Paste")
			(net "GND")
		)
	)
	(footprint ""
		(layer "F.Cu")
		(at 106.250486 -22.271482 180)
		(property "Reference" "Y6000"
			(at 2.285492 -3.005836 0)
			(unlocked yes)
			(layer "F.SilkS")
			(effects
				(font
					(size 0.7874 0.5842)
					(thickness 0.1524)
				)
				(justify left)
			)
		)
		(property "Value" ""
			(at 0 0 180)
			(layer "F.Fab")
			(effects
				(font
					(size 1.27 1.27)
				)
			)
		)
		(duplicate_pad_numbers_are_jumpers no)
		(fp_line
			(start 1.6002 1.9558)
			(end -1.6002 1.9558)
			(stroke
				(width 0.1524)
				(type default)
			)
			(layer "F.SilkS")
		)
		(fp_line
			(start 1.6002 -1.9558)
			(end 1.6002 1.9558)
			(stroke
				(width 0.1524)
				(type default)
			)
			(layer "F.SilkS")
		)
		(fp_line
			(start -1.6002 1.9558)
			(end -1.6002 -1.9558)
			(stroke
				(width 0.1524)
				(type default)
			)
			(layer "F.SilkS")
		)
		(fp_line
			(start -1.6002 -1.9558)
			(end 1.6002 -1.9558)
			(stroke
				(width 0.1524)
				(type default)
			)
			(layer "F.SilkS")
		)
		(fp_poly
			(pts
				(xy -2.88036 -0.26416) (xy -2.88036 -1.33096) (xy -1.78816 -0.74676)
			)
			(stroke
				(width 0)
				(type default)
			)
			(fill yes)
			(layer "F.SilkS")
		)
		(fp_line
			(start 1.299972 1.649984)
			(end -1.299972 1.649984)
			(stroke
				(width 0.1)
				(type default)
			)
			(layer "F.Fab")
		)
		(fp_line
			(start 1.299972 -1.649984)
			(end 1.299972 1.649984)
			(stroke
				(width 0.1)
				(type default)
			)
			(layer "F.Fab")
		)
		(fp_line
			(start -1.299972 1.649984)
			(end -1.299972 -1.649984)
			(stroke
				(width 0.1)
				(type default)
			)
			(layer "F.Fab")
		)
		(fp_line
			(start -1.299972 -1.649984)
			(end 1.299972 -1.649984)
			(stroke
				(width 0.1)
				(type default)
			)
			(layer "F.Fab")
		)
		(fp_poly
			(pts
				(xy -1.7145 -1.0668) (xy -2.8067 -1.651) (xy -2.8067 -0.5842)
			)
			(stroke
				(width 0)
				(type default)
			)
			(fill yes)
			(layer "F.Fab")
		)
		(pad "1" smd rect
			(at -0.849884 -1.100074 180)
			(size 1.2192 1.4224)
			(layers "F.Cu" "F.Mask" "F.Paste")
			(net "XTAL_USB_CPU0_HUB2_XIN")
		)
		(pad "2" smd rect
			(at -0.849884 1.100074 180)
			(size 1.2192 1.4224)
			(layers "F.Cu" "F.Mask" "F.Paste")
			(net "GND")
		)
		(pad "3" smd rect
			(at 0.849884 1.100074 180)
			(size 1.2192 1.4224)
			(layers "F.Cu" "F.Mask" "F.Paste")
			(net "XTAL_USB_CPU0_HUB2_XOUT")
		)
		(pad "4" smd rect
			(at 0.849884 -1.100074 180)
			(size 1.2192 1.4224)
			(layers "F.Cu" "F.Mask" "F.Paste")
			(net "GND")
		)
	)
	(footprint ""
		(layer "F.Cu")
		(at 335.514442 -140.870686)
		(property "Reference" "PU57"
			(at 0.5334 -3.094228 0)
			(unlocked yes)
			(layer "F.SilkS")
			(effects
				(font
					(size 0.7874 0.5842)
					(thickness 0.1524)
				)
				(justify left)
			)
		)
		(property "Value" ""
			(at 0 0 0)
			(layer "F.Fab")
			(effects
				(font
					(size 1.27 1.27)
				)
			)
		)
		(duplicate_pad_numbers_are_jumpers no)
		(fp_line
			(start -1.549908 -2.050034)
			(end -1.549908 -1.9812)
			(stroke
				(width 0.1524)
				(type default)
			)
			(layer "F.SilkS")
		)
		(fp_line
			(start -1.549908 1.9812)
			(end -1.549908 2.050034)
			(stroke
				(width 0.1524)
				(type default)
			)
			(layer "F.SilkS")
		)
		(fp_line
			(start -1.549908 2.050034)
			(end -0.5842 2.050034)
			(stroke
				(width 0.1524)
				(type default)
			)
			(layer "F.SilkS")
		)
		(fp_line
			(start -0.5842 -2.050034)
			(end -1.549908 -2.050034)
			(stroke
				(width 0.1524)
				(type default)
			)
			(layer "F.SilkS")
		)
		(fp_line
			(start 0 2.050034)
			(end 1.549908 2.050034)
			(stroke
				(width 0.1524)
				(type default)
			)
			(layer "F.SilkS")
		)
		(fp_line
			(start 1.549908 -2.050034)
			(end 0.5842 -2.050034)
			(stroke
				(width 0.1524)
				(type default)
			)
			(layer "F.SilkS")
		)
		(fp_line
			(start 1.549908 -1.9812)
			(end 1.549908 -2.050034)
			(stroke
				(width 0.1524)
				(type default)
			)
			(layer "F.SilkS")
		)
		(fp_poly
			(pts
				(xy -1.9304 -1.700022) (xy -2.594864 -1.36779) (xy -2.594864 -2.032254)
			)
			(stroke
				(width 0)
				(type default)
			)
			(fill yes)
			(layer "F.SilkS")
		)
		(fp_line
			(start -1.549908 -2.050034)
			(end -1.549908 2.050034)
			(stroke
				(width 0.1)
				(type default)
			)
			(layer "F.Fab")
		)
		(fp_line
			(start -1.549908 2.050034)
			(end 1.549908 2.050034)
			(stroke
				(width 0.1)
				(type default)
			)
			(layer "F.Fab")
		)
		(fp_line
			(start 1.549908 -2.050034)
			(end -1.549908 -2.050034)
			(stroke
				(width 0.1)
				(type default)
			)
			(layer "F.Fab")
		)
		(fp_line
			(start 1.549908 2.050034)
			(end 1.549908 -2.050034)
			(stroke
				(width 0.1)
				(type default)
			)
			(layer "F.Fab")
		)
		(fp_poly
			(pts
				(xy -2.9464 -2.208022) (xy -2.9464 -1.192022) (xy -1.9304 -1.700022)
			)
			(stroke
				(width 0)
				(type default)
			)
			(fill yes)
			(layer "F.Fab")
		)
		(pad "1" smd circle
			(at -1.35001 -1.700022)
			(size 0 0)
			(layers "F.Cu" "F.Mask" "F.Paste")
			(net "SW_PVDD18_S5_P0_BST")
		)
		(pad "2" smd rect
			(at -1.400048 -1.199896 90)
			(size 0.1778 0.8128)
			(layers "F.Cu" "F.Mask" "F.Paste")
			(net "GND")
		)
		(pad "3" smd rect
			(at -1.400048 -0.8001 90)
			(size 0.1778 0.8128)
			(layers "F.Cu" "F.Mask" "F.Paste")
			(net "PVDD18_S5_P0_CS")
		)
		(pad "4" smd rect
			(at -1.400048 -0.40005 90)
			(size 0.1778 0.8128)
			(layers "F.Cu" "F.Mask" "F.Paste")
			(net "PVDD18_S5_P0_MODE")
		)
		(pad "5" smd rect
			(at -1.400048 0 90)
			(size 0.1778 0.8128)
			(layers "F.Cu" "F.Mask" "F.Paste")
			(net "PVDD18_S5_P0_REF")
		)
		(pad "6" smd rect
			(at -1.400048 0.40005 90)
			(size 0.1778 0.8128)
			(layers "F.Cu" "F.Mask" "F.Paste")
			(net "PVDD18_S5_P0_RGND")
		)
		(pad "7" smd rect
			(at -1.400048 0.8001 90)
			(size 0.1778 0.8128)
			(layers "F.Cu" "F.Mask" "F.Paste")
			(net "PVDD18_S5_P0_FB")
		)
		(pad "8" smd rect
			(at -1.400048 1.199896 90)
			(size 0.1778 0.8128)
			(layers "F.Cu" "F.Mask" "F.Paste")
			(net "PVDD18_S5_P0_EN")
		)
		(pad "9" smd rect
			(at -1.400048 1.700022 90)
			(size 0.3048 0.8128)
			(layers "F.Cu" "F.Mask" "F.Paste")
			(net "PWRGD_PVDD18_S5_P0")
		)
		(pad "10" smd rect
			(at -0.299974 1.299972)
			(size 0.3048 2.0066)
			(layers "F.Cu" "F.Mask" "F.Paste")
			(net "SW_P12V_AUX_PVDD18_S5_P0_FLT")
		)
		(pad "11_18" smd circle
			(at 1.175004 0.275082)
			(size 0 0)
			(layers "F.Cu" "F.Mask" "F.Paste")
			(net "GND")
		)
		(pad "19" smd rect
			(at 1.400048 -1.700022 270)
			(size 0.3048 0.8128)
			(layers "F.Cu" "F.Mask" "F.Paste")
			(net "PVDD18_S5_P0_VCC")
		)
		(pad "20" smd rect
			(at 0.299974 -1.299972)
			(size 0.3048 2.0066)
			(layers "F.Cu" "F.Mask" "F.Paste")
			(net "SW_PVDD18_S5_P0_SW")
		)
		(pad "21" smd rect
			(at -0.299974 -1.299972)
			(size 0.3048 2.0066)
			(layers "F.Cu" "F.Mask" "F.Paste")
			(net "SW_P12V_AUX_PVDD18_S5_P0_FLT")
		)
	)
	(footprint ""
		(layer "F.Cu")
		(at 105.84561 -68.62191 180)
		(property "Reference" "R6217"
			(at 0 0 180)
			(layer "F.SilkS")
			(hide yes)
			(effects
				(font
					(size 1.27 1.27)
				)
			)
		)
		(property "Value" ""
			(at 0 0 180)
			(layer "F.Fab")
			(effects
				(font
					(size 1.27 1.27)
				)
			)
		)
		(duplicate_pad_numbers_are_jumpers no)
		(fp_line
			(start 0.7874 0.4064)
			(end -0.7874 0.4064)
			(stroke
				(width 0.1524)
				(type default)
			)
			(layer "F.SilkS")
		)
		(fp_line
			(start 0.7874 -0.4064)
			(end 0.7874 0.4064)
			(stroke
				(width 0.1524)
				(type default)
			)
			(layer "F.SilkS")
		)
		(fp_line
			(start -0.7874 0.4064)
			(end -0.7874 -0.4064)
			(stroke
				(width 0.1524)
				(type default)
			)
			(layer "F.SilkS")
		)
		(fp_line
			(start -0.7874 -0.4064)
			(end 0.7874 -0.4064)
			(stroke
				(width 0.1524)
				(type default)
			)
			(layer "F.SilkS")
		)
		(fp_line
			(start 0.67945 0.3048)
			(end 0.120396 0.3048)
			(stroke
				(width 0.1)
				(type default)
			)
			(layer "F.Fab")
		)
		(fp_line
			(start 0.67945 -0.3048)
			(end 0.67945 0.3048)
			(stroke
				(width 0.1)
				(type default)
			)
			(layer "F.Fab")
		)
		(fp_line
			(start 0.12065 -0.2794)
			(end 0.12065 -0.3048)
			(stroke
				(width 0.1)
				(type default)
			)
			(layer "F.Fab")
		)
		(fp_line
			(start 0.12065 -0.3048)
			(end 0.67945 -0.3048)
			(stroke
				(width 0.1)
				(type default)
			)
			(layer "F.Fab")
		)
		(fp_line
			(start 0.120396 0.3048)
			(end 0.120396 0.2794)
			(stroke
				(width 0.1)
				(type default)
			)
			(layer "F.Fab")
		)
		(fp_line
			(start 0.120396 0.2794)
			(end -0.12065 0.2794)
			(stroke
				(width 0.1)
				(type default)
			)
			(layer "F.Fab")
		)
		(fp_line
			(start -0.12065 0.3048)
			(end -0.67945 0.3048)
			(stroke
				(width 0.1)
				(type default)
			)
			(layer "F.Fab")
		)
		(fp_line
			(start -0.12065 0.2794)
			(end -0.12065 0.3048)
			(stroke
				(width 0.1)
				(type default)
			)
			(layer "F.Fab")
		)
		(fp_line
			(start -0.12065 -0.2794)
			(end 0.12065 -0.2794)
			(stroke
				(width 0.1)
				(type default)
			)
			(layer "F.Fab")
		)
		(fp_line
			(start -0.12065 -0.305054)
			(end -0.12065 -0.2794)
			(stroke
				(width 0.1)
				(type default)
			)
			(layer "F.Fab")
		)
		(fp_line
			(start -0.67945 0.3048)
			(end -0.67945 -0.305054)
			(stroke
				(width 0.1)
				(type default)
			)
			(layer "F.Fab")
		)
		(fp_line
			(start -0.67945 -0.305054)
			(end -0.12065 -0.305054)
			(stroke
				(width 0.1)
				(type default)
			)
			(layer "F.Fab")
		)
		(pad "1" smd circle
			(at -0.40005 0 180)
			(size 0 0)
			(layers "F.Cu" "F.Mask" "F.Paste")
			(net "USB_CPU0_ADD_A0")
		)
		(pad "2" smd circle
			(at 0.40005 0 180)
			(size 0 0)
			(layers "F.Cu" "F.Mask" "F.Paste")
			(net "GND")
		)
	)
	(footprint ""
		(layer "F.Cu")
		(at 205.243684 -121.960386)
		(property "Reference" "R4146"
			(at 0 0 0)
			(layer "F.SilkS")
			(hide yes)
			(effects
				(font
					(size 1.27 1.27)
				)
			)
		)
		(property "Value" ""
			(at 0 0 0)
			(layer "F.Fab")
			(effects
				(font
					(size 1.27 1.27)
				)
			)
		)
		(duplicate_pad_numbers_are_jumpers no)
		(fp_line
			(start -0.7874 -0.4064)
			(end 0.7874 -0.4064)
			(stroke
				(width 0.1524)
				(type default)
			)
			(layer "F.SilkS")
		)
		(fp_line
			(start -0.7874 0.4064)
			(end -0.7874 -0.4064)
			(stroke
				(width 0.1524)
				(type default)
			)
			(layer "F.SilkS")
		)
		(fp_line
			(start 0.7874 -0.4064)
			(end 0.7874 0.4064)
			(stroke
				(width 0.1524)
				(type default)
			)
			(layer "F.SilkS")
		)
		(fp_line
			(start 0.7874 0.4064)
			(end -0.7874 0.4064)
			(stroke
				(width 0.1524)
				(type default)
			)
			(layer "F.SilkS")
		)
		(fp_line
			(start -0.67945 -0.305054)
			(end -0.12065 -0.305054)
			(stroke
				(width 0.1)
				(type default)
			)
			(layer "F.Fab")
		)
		(fp_line
			(start -0.67945 0.3048)
			(end -0.67945 -0.305054)
			(stroke
				(width 0.1)
				(type default)
			)
			(layer "F.Fab")
		)
		(fp_line
			(start -0.12065 -0.305054)
			(end -0.12065 -0.2794)
			(stroke
				(width 0.1)
				(type default)
			)
			(layer "F.Fab")
		)
		(fp_line
			(start -0.12065 -0.2794)
			(end 0.12065 -0.2794)
			(stroke
				(width 0.1)
				(type default)
			)
			(layer "F.Fab")
		)
		(fp_line
			(start -0.12065 0.2794)
			(end -0.12065 0.3048)
			(stroke
				(width 0.1)
				(type default)
			)
			(layer "F.Fab")
		)
		(fp_line
			(start -0.12065 0.3048)
			(end -0.67945 0.3048)
			(stroke
				(width 0.1)
				(type default)
			)
			(layer "F.Fab")
		)
		(fp_line
			(start 0.120396 0.2794)
			(end -0.12065 0.2794)
			(stroke
				(width 0.1)
				(type default)
			)
			(layer "F.Fab")
		)
		(fp_line
			(start 0.120396 0.3048)
			(end 0.120396 0.2794)
			(stroke
				(width 0.1)
				(type default)
			)
			(layer "F.Fab")
		)
		(fp_line
			(start 0.12065 -0.3048)
			(end 0.67945 -0.3048)
			(stroke
				(width 0.1)
				(type default)
			)
			(layer "F.Fab")
		)
		(fp_line
			(start 0.12065 -0.2794)
			(end 0.12065 -0.3048)
			(stroke
				(width 0.1)
				(type default)
			)
			(layer "F.Fab")
		)
		(fp_line
			(start 0.67945 -0.3048)
			(end 0.67945 0.3048)
			(stroke
				(width 0.1)
				(type default)
			)
			(layer "F.Fab")
		)
		(fp_line
			(start 0.67945 0.3048)
			(end 0.120396 0.3048)
			(stroke
				(width 0.1)
				(type default)
			)
			(layer "F.Fab")
		)
		(pad "1" smd circle
			(at -0.40005 0)
			(size 0 0)
			(layers "F.Cu" "F.Mask" "F.Paste")
			(net "GPU_3V3IO_RSVD3_FFU_ISO_R")
		)
		(pad "2" smd circle
			(at 0.40005 0)
			(size 0 0)
			(layers "F.Cu" "F.Mask" "F.Paste")
			(net "GPU_3V3IO_RSVD3_FFU_ISO")
		)
	)
	(footprint ""
		(layer "F.Cu")
		(at 151.19604 -40.403526 90)
		(property "Reference" "C1861"
			(at 0 0 90)
			(layer "F.SilkS")
			(hide yes)
			(effects
				(font
					(size 1.27 1.27)
				)
			)
		)
		(property "Value" ""
			(at 0 0 90)
			(layer "F.Fab")
			(effects
				(font
					(size 1.27 1.27)
				)
			)
		)
		(duplicate_pad_numbers_are_jumpers no)
		(fp_line
			(start 0.7874 -0.4064)
			(end 0.7874 0.4064)
			(stroke
				(width 0.1524)
				(type default)
			)
			(layer "F.SilkS")
		)
		(fp_line
			(start -0.7874 -0.4064)
			(end 0.7874 -0.4064)
			(stroke
				(width 0.1524)
				(type default)
			)
			(layer "F.SilkS")
		)
		(fp_line
			(start 0.7874 0.4064)
			(end -0.7874 0.4064)
			(stroke
				(width 0.1524)
				(type default)
			)
			(layer "F.SilkS")
		)
		(fp_line
			(start -0.7874 0.4064)
			(end -0.7874 -0.4064)
			(stroke
				(width 0.1524)
				(type default)
			)
			(layer "F.SilkS")
		)
		(fp_line
			(start -0.12065 -0.305054)
			(end -0.12065 -0.2794)
			(stroke
				(width 0.1)
				(type default)
			)
			(layer "F.Fab")
		)
		(fp_line
			(start -0.67945 -0.305054)
			(end -0.12065 -0.305054)
			(stroke
				(width 0.1)
				(type default)
			)
			(layer "F.Fab")
		)
		(fp_line
			(start 0.67945 -0.3048)
			(end 0.67945 0.3048)
			(stroke
				(width 0.1)
				(type default)
			)
			(layer "F.Fab")
		)
		(fp_line
			(start 0.12065 -0.3048)
			(end 0.67945 -0.3048)
			(stroke
				(width 0.1)
				(type default)
			)
			(layer "F.Fab")
		)
		(fp_line
			(start 0.12065 -0.2794)
			(end 0.12065 -0.3048)
			(stroke
				(width 0.1)
				(type default)
			)
			(layer "F.Fab")
		)
		(fp_line
			(start -0.12065 -0.2794)
			(end 0.12065 -0.2794)
			(stroke
				(width 0.1)
				(type default)
			)
			(layer "F.Fab")
		)
		(fp_line
			(start 0.120396 0.2794)
			(end -0.12065 0.2794)
			(stroke
				(width 0.1)
				(type default)
			)
			(layer "F.Fab")
		)
		(fp_line
			(start -0.12065 0.2794)
			(end -0.12065 0.3048)
			(stroke
				(width 0.1)
				(type default)
			)
			(layer "F.Fab")
		)
		(fp_line
			(start 0.67945 0.3048)
			(end 0.120396 0.3048)
			(stroke
				(width 0.1)
				(type default)
			)
			(layer "F.Fab")
		)
		(fp_line
			(start 0.120396 0.3048)
			(end 0.120396 0.2794)
			(stroke
				(width 0.1)
				(type default)
			)
			(layer "F.Fab")
		)
		(fp_line
			(start -0.12065 0.3048)
			(end -0.67945 0.3048)
			(stroke
				(width 0.1)
				(type default)
			)
			(layer "F.Fab")
		)
		(fp_line
			(start -0.67945 0.3048)
			(end -0.67945 -0.305054)
			(stroke
				(width 0.1)
				(type default)
			)
			(layer "F.Fab")
		)
		(pad "1" smd circle
			(at -0.40005 0 90)
			(size 0 0)
			(layers "F.Cu" "F.Mask" "F.Paste")
			(net "P3V3_OCP_V3_2")
		)
		(pad "2" smd circle
			(at 0.40005 0 90)
			(size 0 0)
			(layers "F.Cu" "F.Mask" "F.Paste")
			(net "GND")
		)
	)
)
